(kicad_pcb
	(version 20260206)
	(generator "pcbnew")
	(generator_version "10.0")
	(general
		(thickness 1.6)
		(legacy_teardrops no)
	)
	(paper "A4")
	(title_block
		(title "04192023_DAF0TMB3IC0_F0TG_MB_C_brd_V02_OCP.brd")
		(comment 1 "Grand Teton / footprints 3791-3796 of 8354")
	)
	(layers
		(0 "F.Cu" signal "TOP")
		(4 "In1.Cu" signal "GND")
		(6 "In2.Cu" signal "IN1")
		(8 "In3.Cu" signal "GND1")
		(10 "In4.Cu" signal "IN2")
		(12 "In5.Cu" signal "GND2")
		(14 "In6.Cu" signal "IN3")
		(16 "In7.Cu" signal "GND3")
		(18 "In8.Cu" signal "VCC")
		(20 "In9.Cu" signal "VCC1")
		(22 "In10.Cu" signal "GND4")
		(24 "In11.Cu" signal "IN4")
		(26 "In12.Cu" signal "GND5")
		(28 "In13.Cu" signal "IN5")
		(30 "In14.Cu" signal "GND6")
		(32 "In15.Cu" signal "IN6")
		(34 "In16.Cu" signal "GND7")
		(2 "B.Cu" signal "BOTTOM")
		(9 "F.Adhes" user "F.Adhesive")
		(11 "B.Adhes" user "B.Adhesive")
		(13 "F.Paste" user "Package Geometry/Pastemask Top")
		(15 "B.Paste" user "Package Geometry/Pastemask Bottom")
		(5 "F.SilkS" user "Ref Des/Silkscreen Top")
		(7 "B.SilkS" user "Ref Des/Silkscreen Bottom")
		(1 "F.Mask" user "Board Geometry/Soldermask Top")
		(3 "B.Mask" user "Board Geometry/Soldermask Bottom")
		(17 "Dwgs.User" user "User.Drawings")
		(19 "Cmts.User" user "User.Comments")
		(21 "Eco1.User" user "User.Eco1")
		(23 "Eco2.User" user "User.Eco2")
		(25 "Edge.Cuts" user "Board Geometry/Outline")
		(27 "Margin" user)
		(31 "F.CrtYd" user "Package Geometry/Place Bound Top")
		(29 "B.CrtYd" user "Package Geometry/Place Bound Bottom")
		(35 "F.Fab" user "Ref Des/Assembly Top")
		(33 "B.Fab" user "Ref Des/Assembly Bottom")
	)
	(footprint ""
		(layer "F.Cu")
		(at 58.197496 -344.986864 90)
		(property "Reference" "PR515"
			(at 0 0 90)
			(layer "F.SilkS")
			(hide yes)
			(effects
				(font
					(size 1.27 1.27)
				)
			)
		)
		(property "Value" ""
			(at 0 0 90)
			(layer "F.Fab")
			(effects
				(font
					(size 1.27 1.27)
				)
			)
		)
		(duplicate_pad_numbers_are_jumpers no)
		(fp_line
			(start 0.7874 -0.4064)
			(end 0.7874 0.4064)
			(stroke
				(width 0.1524)
				(type default)
			)
			(layer "F.SilkS")
		)
		(fp_line
			(start -0.7874 -0.4064)
			(end 0.7874 -0.4064)
			(stroke
				(width 0.1524)
				(type default)
			)
			(layer "F.SilkS")
		)
		(fp_line
			(start 0.7874 0.4064)
			(end -0.7874 0.4064)
			(stroke
				(width 0.1524)
				(type default)
			)
			(layer "F.SilkS")
		)
		(fp_line
			(start -0.7874 0.4064)
			(end -0.7874 -0.4064)
			(stroke
				(width 0.1524)
				(type default)
			)
			(layer "F.SilkS")
		)
		(fp_line
			(start -0.12065 -0.305054)
			(end -0.12065 -0.2794)
			(stroke
				(width 0.1)
				(type default)
			)
			(layer "F.Fab")
		)
		(fp_line
			(start -0.67945 -0.305054)
			(end -0.12065 -0.305054)
			(stroke
				(width 0.1)
				(type default)
			)
			(layer "F.Fab")
		)
		(fp_line
			(start 0.67945 -0.3048)
			(end 0.67945 0.3048)
			(stroke
				(width 0.1)
				(type default)
			)
			(layer "F.Fab")
		)
		(fp_line
			(start 0.12065 -0.3048)
			(end 0.67945 -0.3048)
			(stroke
				(width 0.1)
				(type default)
			)
			(layer "F.Fab")
		)
		(fp_line
			(start 0.12065 -0.2794)
			(end 0.12065 -0.3048)
			(stroke
				(width 0.1)
				(type default)
			)
			(layer "F.Fab")
		)
		(fp_line
			(start -0.12065 -0.2794)
			(end 0.12065 -0.2794)
			(stroke
				(width 0.1)
				(type default)
			)
			(layer "F.Fab")
		)
		(fp_line
			(start 0.120396 0.2794)
			(end -0.12065 0.2794)
			(stroke
				(width 0.1)
				(type default)
			)
			(layer "F.Fab")
		)
		(fp_line
			(start -0.12065 0.2794)
			(end -0.12065 0.3048)
			(stroke
				(width 0.1)
				(type default)
			)
			(layer "F.Fab")
		)
		(fp_line
			(start 0.67945 0.3048)
			(end 0.120396 0.3048)
			(stroke
				(width 0.1)
				(type default)
			)
			(layer "F.Fab")
		)
		(fp_line
			(start 0.120396 0.3048)
			(end 0.120396 0.2794)
			(stroke
				(width 0.1)
				(type default)
			)
			(layer "F.Fab")
		)
		(fp_line
			(start -0.12065 0.3048)
			(end -0.67945 0.3048)
			(stroke
				(width 0.1)
				(type default)
			)
			(layer "F.Fab")
		)
		(fp_line
			(start -0.67945 0.3048)
			(end -0.67945 -0.305054)
			(stroke
				(width 0.1)
				(type default)
			)
			(layer "F.Fab")
		)
		(pad "1" smd circle
			(at -0.40005 0 90)
			(size 0 0)
			(layers "F.Cu" "F.Mask" "F.Paste")
			(net "SW_PVDDCR_CPU1_P1_SW4_RC")
		)
		(pad "2" smd circle
			(at 0.40005 0 90)
			(size 0 0)
			(layers "F.Cu" "F.Mask" "F.Paste")
			(net "GND")
		)
	)
	(footprint ""
		(layer "F.Cu")
		(at 409.830778 -168.595548 90)
		(property "Reference" "PC582_SOP0_2"
			(at 0 0 90)
			(layer "F.SilkS")
			(hide yes)
			(effects
				(font
					(size 1.27 1.27)
				)
			)
		)
		(property "Value" ""
			(at 0 0 90)
			(layer "F.Fab")
			(effects
				(font
					(size 1.27 1.27)
				)
			)
		)
		(duplicate_pad_numbers_are_jumpers no)
		(fp_line
			(start 0.7874 -0.4064)
			(end 0.7874 0.4064)
			(stroke
				(width 0.1524)
				(type default)
			)
			(layer "F.SilkS")
		)
		(fp_line
			(start -0.7874 -0.4064)
			(end 0.7874 -0.4064)
			(stroke
				(width 0.1524)
				(type default)
			)
			(layer "F.SilkS")
		)
		(fp_line
			(start 0.7874 0.4064)
			(end -0.7874 0.4064)
			(stroke
				(width 0.1524)
				(type default)
			)
			(layer "F.SilkS")
		)
		(fp_line
			(start -0.7874 0.4064)
			(end -0.7874 -0.4064)
			(stroke
				(width 0.1524)
				(type default)
			)
			(layer "F.SilkS")
		)
		(fp_line
			(start -0.12065 -0.305054)
			(end -0.12065 -0.2794)
			(stroke
				(width 0.1)
				(type default)
			)
			(layer "F.Fab")
		)
		(fp_line
			(start -0.67945 -0.305054)
			(end -0.12065 -0.305054)
			(stroke
				(width 0.1)
				(type default)
			)
			(layer "F.Fab")
		)
		(fp_line
			(start 0.67945 -0.3048)
			(end 0.67945 0.3048)
			(stroke
				(width 0.1)
				(type default)
			)
			(layer "F.Fab")
		)
		(fp_line
			(start 0.12065 -0.3048)
			(end 0.67945 -0.3048)
			(stroke
				(width 0.1)
				(type default)
			)
			(layer "F.Fab")
		)
		(fp_line
			(start 0.12065 -0.2794)
			(end 0.12065 -0.3048)
			(stroke
				(width 0.1)
				(type default)
			)
			(layer "F.Fab")
		)
		(fp_line
			(start -0.12065 -0.2794)
			(end 0.12065 -0.2794)
			(stroke
				(width 0.1)
				(type default)
			)
			(layer "F.Fab")
		)
		(fp_line
			(start 0.120396 0.2794)
			(end -0.12065 0.2794)
			(stroke
				(width 0.1)
				(type default)
			)
			(layer "F.Fab")
		)
		(fp_line
			(start -0.12065 0.2794)
			(end -0.12065 0.3048)
			(stroke
				(width 0.1)
				(type default)
			)
			(layer "F.Fab")
		)
		(fp_line
			(start 0.67945 0.3048)
			(end 0.120396 0.3048)
			(stroke
				(width 0.1)
				(type default)
			)
			(layer "F.Fab")
		)
		(fp_line
			(start 0.120396 0.3048)
			(end 0.120396 0.2794)
			(stroke
				(width 0.1)
				(type default)
			)
			(layer "F.Fab")
		)
		(fp_line
			(start -0.12065 0.3048)
			(end -0.67945 0.3048)
			(stroke
				(width 0.1)
				(type default)
			)
			(layer "F.Fab")
		)
		(fp_line
			(start -0.67945 0.3048)
			(end -0.67945 -0.305054)
			(stroke
				(width 0.1)
				(type default)
			)
			(layer "F.Fab")
		)
		(pad "1" smd circle
			(at -0.40005 0 90)
			(size 0 0)
			(layers "F.Cu" "F.Mask" "F.Paste")
			(net "PVDDCR_CPU0_P0_PVCC")
		)
		(pad "2" smd circle
			(at 0.40005 0 90)
			(size 0 0)
			(layers "F.Cu" "F.Mask" "F.Paste")
			(net "GND")
		)
	)
	(footprint ""
		(layer "F.Cu")
		(at 219.974922 -73.484994 180)
		(property "Reference" "PC2210"
			(at 0 0 180)
			(layer "F.SilkS")
			(hide yes)
			(effects
				(font
					(size 1.27 1.27)
				)
			)
		)
		(property "Value" ""
			(at 0 0 180)
			(layer "F.Fab")
			(effects
				(font
					(size 1.27 1.27)
				)
			)
		)
		(duplicate_pad_numbers_are_jumpers no)
		(fp_line
			(start 0.7874 0.4064)
			(end -0.7874 0.4064)
			(stroke
				(width 0.1524)
				(type default)
			)
			(layer "F.SilkS")
		)
		(fp_line
			(start 0.7874 -0.4064)
			(end 0.7874 0.4064)
			(stroke
				(width 0.1524)
				(type default)
			)
			(layer "F.SilkS")
		)
		(fp_line
			(start -0.7874 0.4064)
			(end -0.7874 -0.4064)
			(stroke
				(width 0.1524)
				(type default)
			)
			(layer "F.SilkS")
		)
		(fp_line
			(start -0.7874 -0.4064)
			(end 0.7874 -0.4064)
			(stroke
				(width 0.1524)
				(type default)
			)
			(layer "F.SilkS")
		)
		(fp_line
			(start 0.67945 0.3048)
			(end 0.120396 0.3048)
			(stroke
				(width 0.1)
				(type default)
			)
			(layer "F.Fab")
		)
		(fp_line
			(start 0.67945 -0.3048)
			(end 0.67945 0.3048)
			(stroke
				(width 0.1)
				(type default)
			)
			(layer "F.Fab")
		)
		(fp_line
			(start 0.12065 -0.2794)
			(end 0.12065 -0.3048)
			(stroke
				(width 0.1)
				(type default)
			)
			(layer "F.Fab")
		)
		(fp_line
			(start 0.12065 -0.3048)
			(end 0.67945 -0.3048)
			(stroke
				(width 0.1)
				(type default)
			)
			(layer "F.Fab")
		)
		(fp_line
			(start 0.120396 0.3048)
			(end 0.120396 0.2794)
			(stroke
				(width 0.1)
				(type default)
			)
			(layer "F.Fab")
		)
		(fp_line
			(start 0.120396 0.2794)
			(end -0.12065 0.2794)
			(stroke
				(width 0.1)
				(type default)
			)
			(layer "F.Fab")
		)
		(fp_line
			(start -0.12065 0.3048)
			(end -0.67945 0.3048)
			(stroke
				(width 0.1)
				(type default)
			)
			(layer "F.Fab")
		)
		(fp_line
			(start -0.12065 0.2794)
			(end -0.12065 0.3048)
			(stroke
				(width 0.1)
				(type default)
			)
			(layer "F.Fab")
		)
		(fp_line
			(start -0.12065 -0.2794)
			(end 0.12065 -0.2794)
			(stroke
				(width 0.1)
				(type default)
			)
			(layer "F.Fab")
		)
		(fp_line
			(start -0.12065 -0.305054)
			(end -0.12065 -0.2794)
			(stroke
				(width 0.1)
				(type default)
			)
			(layer "F.Fab")
		)
		(fp_line
			(start -0.67945 0.3048)
			(end -0.67945 -0.305054)
			(stroke
				(width 0.1)
				(type default)
			)
			(layer "F.Fab")
		)
		(fp_line
			(start -0.67945 -0.305054)
			(end -0.12065 -0.305054)
			(stroke
				(width 0.1)
				(type default)
			)
			(layer "F.Fab")
		)
		(pad "1" smd circle
			(at -0.40005 0 180)
			(size 0 0)
			(layers "F.Cu" "F.Mask" "F.Paste")
			(net "P3V3_E1S_VCC_0")
		)
		(pad "2" smd circle
			(at 0.40005 0 180)
			(size 0 0)
			(layers "F.Cu" "F.Mask" "F.Paste")
			(net "GND")
		)
	)
	(footprint ""
		(layer "F.Cu")
		(at 319.22339 -192.89776 -90)
		(property "Reference" "R427"
			(at 0 0 270)
			(layer "F.SilkS")
			(hide yes)
			(effects
				(font
					(size 1.27 1.27)
				)
			)
		)
		(property "Value" ""
			(at 0 0 270)
			(layer "F.Fab")
			(effects
				(font
					(size 1.27 1.27)
				)
			)
		)
		(duplicate_pad_numbers_are_jumpers no)
		(fp_line
			(start -0.7874 0.4064)
			(end -0.7874 -0.4064)
			(stroke
				(width 0.1524)
				(type default)
			)
			(layer "F.SilkS")
		)
		(fp_line
			(start 0.7874 0.4064)
			(end -0.7874 0.4064)
			(stroke
				(width 0.1524)
				(type default)
			)
			(layer "F.SilkS")
		)
		(fp_line
			(start -0.7874 -0.4064)
			(end 0.7874 -0.4064)
			(stroke
				(width 0.1524)
				(type default)
			)
			(layer "F.SilkS")
		)
		(fp_line
			(start 0.7874 -0.4064)
			(end 0.7874 0.4064)
			(stroke
				(width 0.1524)
				(type default)
			)
			(layer "F.SilkS")
		)
		(fp_line
			(start -0.67945 0.3048)
			(end -0.67945 -0.305054)
			(stroke
				(width 0.1)
				(type default)
			)
			(layer "F.Fab")
		)
		(fp_line
			(start -0.12065 0.3048)
			(end -0.67945 0.3048)
			(stroke
				(width 0.1)
				(type default)
			)
			(layer "F.Fab")
		)
		(fp_line
			(start 0.120396 0.3048)
			(end 0.120396 0.2794)
			(stroke
				(width 0.1)
				(type default)
			)
			(layer "F.Fab")
		)
		(fp_line
			(start 0.67945 0.3048)
			(end 0.120396 0.3048)
			(stroke
				(width 0.1)
				(type default)
			)
			(layer "F.Fab")
		)
		(fp_line
			(start -0.12065 0.2794)
			(end -0.12065 0.3048)
			(stroke
				(width 0.1)
				(type default)
			)
			(layer "F.Fab")
		)
		(fp_line
			(start 0.120396 0.2794)
			(end -0.12065 0.2794)
			(stroke
				(width 0.1)
				(type default)
			)
			(layer "F.Fab")
		)
		(fp_line
			(start -0.12065 -0.2794)
			(end 0.12065 -0.2794)
			(stroke
				(width 0.1)
				(type default)
			)
			(layer "F.Fab")
		)
		(fp_line
			(start 0.12065 -0.2794)
			(end 0.12065 -0.3048)
			(stroke
				(width 0.1)
				(type default)
			)
			(layer "F.Fab")
		)
		(fp_line
			(start 0.12065 -0.3048)
			(end 0.67945 -0.3048)
			(stroke
				(width 0.1)
				(type default)
			)
			(layer "F.Fab")
		)
		(fp_line
			(start 0.67945 -0.3048)
			(end 0.67945 0.3048)
			(stroke
				(width 0.1)
				(type default)
			)
			(layer "F.Fab")
		)
		(fp_line
			(start -0.67945 -0.305054)
			(end -0.12065 -0.305054)
			(stroke
				(width 0.1)
				(type default)
			)
			(layer "F.Fab")
		)
		(fp_line
			(start -0.12065 -0.305054)
			(end -0.12065 -0.2794)
			(stroke
				(width 0.1)
				(type default)
			)
			(layer "F.Fab")
		)
		(pad "1" smd rect
			(at -0.40005 0 90)
			(size 0.4572 0.508)
			(layers "F.Cu" "F.Mask" "F.Paste")
			(net "I3C_0_SPD_DDRAF_CPU0_SDA")
		)
		(pad "2" smd rect
			(at 0.40005 0 90)
			(size 0.4572 0.508)
			(layers "F.Cu" "F.Mask" "F.Paste")
			(net "I3C_0_SPD_DDRAF_CPU0_R_SDA")
		)
	)
	(footprint ""
		(layer "F.Cu")
		(at 197.269608 -124.801376)
		(property "Reference" "R1527"
			(at 0 0 0)
			(layer "F.SilkS")
			(hide yes)
			(effects
				(font
					(size 1.27 1.27)
				)
			)
		)
		(property "Value" ""
			(at 0 0 0)
			(layer "F.Fab")
			(effects
				(font
					(size 1.27 1.27)
				)
			)
		)
		(duplicate_pad_numbers_are_jumpers no)
		(fp_line
			(start -0.7874 -0.4064)
			(end 0.7874 -0.4064)
			(stroke
				(width 0.1524)
				(type default)
			)
			(layer "F.SilkS")
		)
		(fp_line
			(start -0.7874 0.4064)
			(end -0.7874 -0.4064)
			(stroke
				(width 0.1524)
				(type default)
			)
			(layer "F.SilkS")
		)
		(fp_line
			(start 0.7874 -0.4064)
			(end 0.7874 0.4064)
			(stroke
				(width 0.1524)
				(type default)
			)
			(layer "F.SilkS")
		)
		(fp_line
			(start 0.7874 0.4064)
			(end -0.7874 0.4064)
			(stroke
				(width 0.1524)
				(type default)
			)
			(layer "F.SilkS")
		)
		(fp_line
			(start -0.67945 -0.305054)
			(end -0.12065 -0.305054)
			(stroke
				(width 0.1)
				(type default)
			)
			(layer "F.Fab")
		)
		(fp_line
			(start -0.67945 0.3048)
			(end -0.67945 -0.305054)
			(stroke
				(width 0.1)
				(type default)
			)
			(layer "F.Fab")
		)
		(fp_line
			(start -0.12065 -0.305054)
			(end -0.12065 -0.2794)
			(stroke
				(width 0.1)
				(type default)
			)
			(layer "F.Fab")
		)
		(fp_line
			(start -0.12065 -0.2794)
			(end 0.12065 -0.2794)
			(stroke
				(width 0.1)
				(type default)
			)
			(layer "F.Fab")
		)
		(fp_line
			(start -0.12065 0.2794)
			(end -0.12065 0.3048)
			(stroke
				(width 0.1)
				(type default)
			)
			(layer "F.Fab")
		)
		(fp_line
			(start -0.12065 0.3048)
			(end -0.67945 0.3048)
			(stroke
				(width 0.1)
				(type default)
			)
			(layer "F.Fab")
		)
		(fp_line
			(start 0.120396 0.2794)
			(end -0.12065 0.2794)
			(stroke
				(width 0.1)
				(type default)
			)
			(layer "F.Fab")
		)
		(fp_line
			(start 0.120396 0.3048)
			(end 0.120396 0.2794)
			(stroke
				(width 0.1)
				(type default)
			)
			(layer "F.Fab")
		)
		(fp_line
			(start 0.12065 -0.3048)
			(end 0.67945 -0.3048)
			(stroke
				(width 0.1)
				(type default)
			)
			(layer "F.Fab")
		)
		(fp_line
			(start 0.12065 -0.2794)
			(end 0.12065 -0.3048)
			(stroke
				(width 0.1)
				(type default)
			)
			(layer "F.Fab")
		)
		(fp_line
			(start 0.67945 -0.3048)
			(end 0.67945 0.3048)
			(stroke
				(width 0.1)
				(type default)
			)
			(layer "F.Fab")
		)
		(fp_line
			(start 0.67945 0.3048)
			(end 0.120396 0.3048)
			(stroke
				(width 0.1)
				(type default)
			)
			(layer "F.Fab")
		)
		(pad "1" smd circle
			(at -0.40005 0)
			(size 0 0)
			(layers "F.Cu" "F.Mask" "F.Paste")
			(net "PRSNT_HDT_N")
		)
		(pad "2" smd circle
			(at 0.40005 0)
			(size 0 0)
			(layers "F.Cu" "F.Mask" "F.Paste")
			(net "P3V3_AUX")
		)
	)
	(footprint ""
		(layer "F.Cu")
		(at 293.038022 -53.29809)
		(property "Reference" "R424"
			(at 0 0 0)
			(layer "F.SilkS")
			(hide yes)
			(effects
				(font
					(size 1.27 1.27)
				)
			)
		)
		(property "Value" ""
			(at 0 0 0)
			(layer "F.Fab")
			(effects
				(font
					(size 1.27 1.27)
				)
			)
		)
		(duplicate_pad_numbers_are_jumpers no)
		(fp_line
			(start -0.7874 -0.4064)
			(end 0.7874 -0.4064)
			(stroke
				(width 0.1524)
				(type default)
			)
			(layer "F.SilkS")
		)
		(fp_line
			(start -0.7874 0.4064)
			(end -0.7874 -0.4064)
			(stroke
				(width 0.1524)
				(type default)
			)
			(layer "F.SilkS")
		)
		(fp_line
			(start 0.7874 -0.4064)
			(end 0.7874 0.4064)
			(stroke
				(width 0.1524)
				(type default)
			)
			(layer "F.SilkS")
		)
		(fp_line
			(start 0.7874 0.4064)
			(end -0.7874 0.4064)
			(stroke
				(width 0.1524)
				(type default)
			)
			(layer "F.SilkS")
		)
		(fp_line
			(start -0.67945 -0.305054)
			(end -0.12065 -0.305054)
			(stroke
				(width 0.1)
				(type default)
			)
			(layer "F.Fab")
		)
		(fp_line
			(start -0.67945 0.3048)
			(end -0.67945 -0.305054)
			(stroke
				(width 0.1)
				(type default)
			)
			(layer "F.Fab")
		)
		(fp_line
			(start -0.12065 -0.305054)
			(end -0.12065 -0.2794)
			(stroke
				(width 0.1)
				(type default)
			)
			(layer "F.Fab")
		)
		(fp_line
			(start -0.12065 -0.2794)
			(end 0.12065 -0.2794)
			(stroke
				(width 0.1)
				(type default)
			)
			(layer "F.Fab")
		)
		(fp_line
			(start -0.12065 0.2794)
			(end -0.12065 0.3048)
			(stroke
				(width 0.1)
				(type default)
			)
			(layer "F.Fab")
		)
		(fp_line
			(start -0.12065 0.3048)
			(end -0.67945 0.3048)
			(stroke
				(width 0.1)
				(type default)
			)
			(layer "F.Fab")
		)
		(fp_line
			(start 0.120396 0.2794)
			(end -0.12065 0.2794)
			(stroke
				(width 0.1)
				(type default)
			)
			(layer "F.Fab")
		)
		(fp_line
			(start 0.120396 0.3048)
			(end 0.120396 0.2794)
			(stroke
				(width 0.1)
				(type default)
			)
			(layer "F.Fab")
		)
		(fp_line
			(start 0.12065 -0.3048)
			(end 0.67945 -0.3048)
			(stroke
				(width 0.1)
				(type default)
			)
			(layer "F.Fab")
		)
		(fp_line
			(start 0.12065 -0.2794)
			(end 0.12065 -0.3048)
			(stroke
				(width 0.1)
				(type default)
			)
			(layer "F.Fab")
		)
		(fp_line
			(start 0.67945 -0.3048)
			(end 0.67945 0.3048)
			(stroke
				(width 0.1)
				(type default)
			)
			(layer "F.Fab")
		)
		(fp_line
			(start 0.67945 0.3048)
			(end 0.120396 0.3048)
			(stroke
				(width 0.1)
				(type default)
			)
			(layer "F.Fab")
		)
		(pad "1" smd circle
			(at -0.40005 0)
			(size 0 0)
			(layers "F.Cu" "F.Mask" "F.Paste")
			(net "PVDD18_S5_P0")
		)
		(pad "2" smd circle
			(at 0.40005 0)
			(size 0 0)
			(layers "F.Cu" "F.Mask" "F.Paste")
			(net "CPU0_PWR_BTN_N")
		)
	)
)
